(kicad_pcb
	(version 20241229)
	(generator "pcbnew")
	(generator_version "9.0")
	(general
		(thickness 1.294)
		(legacy_teardrops no)
	)
	(paper "A3")
	(title_block
		(title "Kintex 410T devboard")
		(date "2024-04-03")
		(rev "1.1.2")
		(comment 9 "footprints 235-238 of 975")
	)
	(layers
		(0 "F.Cu" mixed)
		(4 "In1.Cu" power)
		(6 "In2.Cu" power)
		(8 "In3.Cu" mixed)
		(10 "In4.Cu" power)
		(12 "In5.Cu" mixed)
		(14 "In6.Cu" power)
		(16 "In7.Cu" mixed)
		(18 "In8.Cu" power)
		(2 "B.Cu" mixed)
		(9 "F.Adhes" user "F.Adhesive")
		(11 "B.Adhes" user "B.Adhesive")
		(13 "F.Paste" user)
		(15 "B.Paste" user)
		(5 "F.SilkS" user "F.Silkscreen")
		(7 "B.SilkS" user "B.Silkscreen")
		(1 "F.Mask" user)
		(3 "B.Mask" user)
		(17 "Dwgs.User" user "User.Drawings")
		(19 "Cmts.User" user "User.Comments")
		(21 "Eco1.User" user "User.Eco1")
		(23 "Eco2.User" user "User.Eco2")
		(25 "Edge.Cuts" user)
		(27 "Margin" user)
		(31 "F.CrtYd" user "F.Courtyard")
		(29 "B.CrtYd" user "B.Courtyard")
		(35 "F.Fab" user)
		(33 "B.Fab" user)
	)
	(footprint "antmicro-footprints:R_0402_1005Metric"
		(layer "F.Cu")
		(at 238 134.7 -90)
		(descr "Resistor SMD 0402")
		(tags "resistor SMD 0402")
		(property "Reference" "R187"
			(at -1.625 -3.925 90)
			(layer "F.SilkS")
			(effects
				(font
					(size 0.7 0.7)
					(thickness 0.15)
				)
				(justify left bottom)
			)
		)
		(property "Value" "R_0R_0402"
			(at 0 1.4 270)
			(layer "F.Fab")
			(effects
				(font
					(size 0.7 0.7)
					(thickness 0.15)
				)
				(justify left bottom)
			)
		)
		(property "Description" "SMD Chip Resistor, Jumper, 0 ohm, 100 mW, 0402 [1005 Metric], Thick Film, General Purpose"
			(at 0 0 270)
			(layer "F.Fab")
			(hide yes)
			(effects
				(font
					(size 1.27 1.27)
					(thickness 0.15)
				)
			)
		)
		(property "Author" "Antmicro"
			(at 103.3 372.7 0)
			(layer "F.Fab")
			(hide yes)
			(effects
				(font
					(size 1 1)
					(thickness 0.15)
				)
			)
		)
		(property "Current" "1A"
			(at 103.3 372.7 0)
			(layer "F.Fab")
			(hide yes)
			(effects
				(font
					(size 1 1)
					(thickness 0.15)
				)
			)
		)
		(property "DNP" "DNP"
			(at 103.3 372.7 0)
			(layer "F.Fab")
			(hide yes)
			(effects
				(font
					(size 1 1)
					(thickness 0.15)
				)
			)
		)
		(property "License" "Apache-2.0"
			(at 103.3 372.7 0)
			(layer "F.Fab")
			(hide yes)
			(effects
				(font
					(size 1 1)
					(thickness 0.15)
				)
			)
		)
		(property "MPN" "ERJ2GE0R00X"
			(at 103.3 372.7 0)
			(layer "F.Fab")
			(hide yes)
			(effects
				(font
					(size 1 1)
					(thickness 0.15)
				)
			)
		)
		(property "Manufacturer" "Panasonic"
			(at 103.3 372.7 0)
			(layer "F.Fab")
			(hide yes)
			(effects
				(font
					(size 1 1)
					(thickness 0.15)
				)
			)
		)
		(property "Tolerance" ""
			(at 103.3 372.7 0)
			(layer "F.Fab")
			(hide yes)
			(effects
				(font
					(size 1 1)
					(thickness 0.15)
				)
			)
		)
		(property "Val" "0R"
			(at 103.3 372.7 0)
			(layer "F.Fab")
			(hide yes)
			(effects
				(font
					(size 1 1)
					(thickness 0.15)
				)
			)
		)
		(property "dnp" ""
			(at 103.3 372.7 0)
			(layer "F.Fab")
			(hide yes)
			(effects
				(font
					(size 1 1)
					(thickness 0.15)
				)
			)
		)
		(property "exclude_from_bom" ""
			(at 103.3 372.7 0)
			(layer "F.Fab")
			(hide yes)
			(effects
				(font
					(size 1 1)
					(thickness 0.15)
				)
			)
		)
		(sheetname "USB PHY")
		(sheetfile "usb-phy.kicad_sch")
		(attr smd exclude_from_bom)
		(fp_rect
			(start -0.925 -0.47)
			(end 0.925 0.47)
			(stroke
				(width 0.05)
				(type default)
			)
			(fill no)
			(layer "F.CrtYd")
		)
		(fp_rect
			(start -0.5 -0.25)
			(end 0.5 0.25)
			(stroke
				(width 0.15)
				(type solid)
			)
			(fill no)
			(layer "F.Fab")
		)
		(pad "1" smd roundrect
			(at -0.48 0 270)
			(size 0.59 0.64)
			(layers "F.Cu" "F.Mask" "F.Paste")
			(roundrect_rratio 0.25)
			(net 940 "/USB PHY/I2C_EN")
			(pintype "passive")
		)
		(pad "2" smd roundrect
			(at 0.48 0 270)
			(size 0.59 0.64)
			(layers "F.Cu" "F.Mask" "F.Paste")
			(roundrect_rratio 0.25)
			(net 379 "Net-(U24-OE)")
			(pintype "passive")
		)
	)
	(footprint "antmicro-footprints:C_0402_1005Metric"
		(layer "F.Cu")
		(at 191.301 107.749 90)
		(descr "Capacitor SMD 0402")
		(tags "capacitor SMD 0402")
		(property "Reference" "C226"
			(at -1.351 -0.501 90)
			(layer "F.SilkS")
			(effects
				(font
					(size 0.7 0.7)
					(thickness 0.15)
				)
				(justify left bottom)
			)
		)
		(property "Value" "C_1u_0402"
			(at 0 1.4 90)
			(layer "F.Fab")
			(effects
				(font
					(size 0.7 0.7)
					(thickness 0.15)
				)
				(justify left bottom)
			)
		)
		(property "Description" "SMD Multilayer Ceramic Capacitor, 1 µF, 10 V, 0402 [1005 Metric], ± 10%, X6S, C"
			(at 0 0 90)
			(layer "F.Fab")
			(hide yes)
			(effects
				(font
					(size 1.27 1.27)
					(thickness 0.15)
				)
			)
		)
		(property "Author" "Antmicro"
			(at 299.05 -83.552 0)
			(layer "F.Fab")
			(hide yes)
			(effects
				(font
					(size 1 1)
					(thickness 0.15)
				)
			)
		)
		(property "Dielectric" ""
			(at 299.05 -83.552 0)
			(layer "F.Fab")
			(hide yes)
			(effects
				(font
					(size 1 1)
					(thickness 0.15)
				)
			)
		)
		(property "License" "Apache-2.0"
			(at 299.05 -83.552 0)
			(layer "F.Fab")
			(hide yes)
			(effects
				(font
					(size 1 1)
					(thickness 0.15)
				)
			)
		)
		(property "MPN" "C1005X6S1A105K050BC"
			(at 299.05 -83.552 0)
			(layer "F.Fab")
			(hide yes)
			(effects
				(font
					(size 1 1)
					(thickness 0.15)
				)
			)
		)
		(property "Manufacturer" "TDK"
			(at 299.05 -83.552 0)
			(layer "F.Fab")
			(hide yes)
			(effects
				(font
					(size 1 1)
					(thickness 0.15)
				)
			)
		)
		(property "Val" "1u"
			(at 299.05 -83.552 0)
			(layer "F.Fab")
			(hide yes)
			(effects
				(font
					(size 1 1)
					(thickness 0.15)
				)
			)
		)
		(property "Voltage" ""
			(at 299.05 -83.552 0)
			(layer "F.Fab")
			(hide yes)
			(effects
				(font
					(size 1 1)
					(thickness 0.15)
				)
			)
		)
		(sheetname "USB PHY")
		(sheetfile "usb-phy.kicad_sch")
		(attr smd)
		(fp_rect
			(start -0.925 -0.47)
			(end 0.925 0.47)
			(stroke
				(width 0.05)
				(type default)
			)
			(fill no)
			(layer "F.CrtYd")
		)
		(fp_line
			(start 0.504 -0.25)
			(end 0.504 0.248)
			(stroke
				(width 0.15)
				(type solid)
			)
			(layer "F.Fab")
		)
		(fp_line
			(start -0.494 -0.25)
			(end 0.504 -0.25)
			(stroke
				(width 0.15)
				(type solid)
			)
			(layer "F.Fab")
		)
		(fp_line
			(start 0.504 0.248)
			(end -0.494 0.248)
			(stroke
				(width 0.15)
				(type solid)
			)
			(layer "F.Fab")
		)
		(fp_line
			(start -0.494 0.248)
			(end -0.494 -0.25)
			(stroke
				(width 0.15)
				(type solid)
			)
			(layer "F.Fab")
		)
		(pad "1" smd roundrect
			(at -0.48 0 90)
			(size 0.59 0.64)
			(layers "F.Cu" "F.Mask" "F.Paste")
			(roundrect_rratio 0.25)
			(net 1 "GND")
			(pintype "passive")
		)
		(pad "2" smd roundrect
			(at 0.48 0 90)
			(size 0.59 0.64)
			(layers "F.Cu" "F.Mask" "F.Paste")
			(roundrect_rratio 0.25)
			(net 24 "+3V3")
			(pintype "passive")
		)
	)
	(footprint "antmicro-footprints:C_0402_1005Metric"
		(layer "F.Cu")
		(at 230.4 147.4)
		(descr "Capacitor SMD 0402")
		(tags "capacitor SMD 0402")
		(property "Reference" "C252"
			(at -0.85 -0.5 0)
			(layer "F.SilkS")
			(effects
				(font
					(size 0.7 0.7)
					(thickness 0.15)
				)
				(justify left bottom)
			)
		)
		(property "Value" "C_22p_0402"
			(at 0 1.4 0)
			(layer "F.Fab")
			(effects
				(font
					(size 0.7 0.7)
					(thickness 0.15)
				)
				(justify left bottom)
			)
		)
		(property "Description" "SMD Multilayer Ceramic Capacitor, 22 pF, 50 V, 0402 [1005 Metric], ± 5%, C0G / NP0, CC Series"
			(at 0 0 0)
			(layer "F.Fab")
			(hide yes)
			(effects
				(font
					(size 1.27 1.27)
					(thickness 0.15)
				)
			)
		)
		(property "Author" "Antmicro"
			(at 0 0 0)
			(layer "F.Fab")
			(hide yes)
			(effects
				(font
					(size 1 1)
					(thickness 0.15)
				)
			)
		)
		(property "Dielectric" ""
			(at 0 0 0)
			(layer "F.Fab")
			(hide yes)
			(effects
				(font
					(size 1 1)
					(thickness 0.15)
				)
			)
		)
		(property "License" "Apache-2.0"
			(at 0 0 0)
			(layer "F.Fab")
			(hide yes)
			(effects
				(font
					(size 1 1)
					(thickness 0.15)
				)
			)
		)
		(property "MPN" "CC0402JRNPO9BN220"
			(at 0 0 0)
			(layer "F.Fab")
			(hide yes)
			(effects
				(font
					(size 1 1)
					(thickness 0.15)
				)
			)
		)
		(property "Manufacturer" "YAGEO"
			(at 0 0 0)
			(layer "F.Fab")
			(hide yes)
			(effects
				(font
					(size 1 1)
					(thickness 0.15)
				)
			)
		)
		(property "Val" "22p"
			(at 0 0 0)
			(layer "F.Fab")
			(hide yes)
			(effects
				(font
					(size 1 1)
					(thickness 0.15)
				)
			)
		)
		(property "Voltage" ""
			(at 0 0 0)
			(layer "F.Fab")
			(hide yes)
			(effects
				(font
					(size 1 1)
					(thickness 0.15)
				)
			)
		)
		(sheetname "HDMI + Ethernet")
		(sheetfile "hdmi-ethernet.kicad_sch")
		(attr smd)
		(fp_rect
			(start -0.925 -0.47)
			(end 0.925 0.47)
			(stroke
				(width 0.05)
				(type default)
			)
			(fill no)
			(layer "F.CrtYd")
		)
		(fp_line
			(start -0.494 -0.25)
			(end 0.504 -0.25)
			(stroke
				(width 0.15)
				(type solid)
			)
			(layer "F.Fab")
		)
		(fp_line
			(start -0.494 0.248)
			(end -0.494 -0.25)
			(stroke
				(width 0.15)
				(type solid)
			)
			(layer "F.Fab")
		)
		(fp_line
			(start 0.504 -0.25)
			(end 0.504 0.248)
			(stroke
				(width 0.15)
				(type solid)
			)
			(layer "F.Fab")
		)
		(fp_line
			(start 0.504 0.248)
			(end -0.494 0.248)
			(stroke
				(width 0.15)
				(type solid)
			)
			(layer "F.Fab")
		)
		(pad "1" smd roundrect
			(at -0.48 0)
			(size 0.59 0.64)
			(layers "F.Cu" "F.Mask" "F.Paste")
			(roundrect_rratio 0.25)
			(net 1 "GND")
			(pintype "passive")
		)
		(pad "2" smd roundrect
			(at 0.48 0)
			(size 0.59 0.64)
			(layers "F.Cu" "F.Mask" "F.Paste")
			(roundrect_rratio 0.25)
			(net 716 "/HDMI + Ethernet/ETH_XI")
			(pintype "passive")
		)
	)
	(footprint "antmicro-footprints:C_0402_1005Metric"
		(layer "F.Cu")
		(at 219.2 138.425 180)
		(descr "Capacitor SMD 0402")
		(tags "capacitor SMD 0402")
		(property "Reference" "C372"
			(at 3.65 -0.375 180)
			(layer "F.SilkS")
			(effects
				(font
					(size 0.7 0.7)
					(thickness 0.15)
				)
				(justify left bottom)
			)
		)
		(property "Value" "C_100n_0402"
			(at 0 1.4 180)
			(layer "F.Fab")
			(effects
				(font
					(size 0.7 0.7)
					(thickness 0.15)
				)
				(justify left bottom)
			)
		)
		(property "Description" "SMD Multilayer Ceramic Capacitor, 0.1 µF, 50 V, 0402 [1005 Metric], ± 10%, X5R, GRM Series"
			(at 0 0 180)
			(layer "F.Fab")
			(hide yes)
			(effects
				(font
					(size 1.27 1.27)
					(thickness 0.15)
				)
			)
		)
		(property "Author" "Antmicro"
			(at 438.4 276.85 0)
			(layer "F.Fab")
			(hide yes)
			(effects
				(font
					(size 1 1)
					(thickness 0.15)
				)
			)
		)
		(property "Dielectric" "X5R"
			(at 438.4 276.85 0)
			(layer "F.Fab")
			(hide yes)
			(effects
				(font
					(size 1 1)
					(thickness 0.15)
				)
			)
		)
		(property "License" "Apache-2.0"
			(at 438.4 276.85 0)
			(layer "F.Fab")
			(hide yes)
			(effects
				(font
					(size 1 1)
					(thickness 0.15)
				)
			)
		)
		(property "MPN" "GRM155R61H104KE14D"
			(at 438.4 276.85 0)
			(layer "F.Fab")
			(hide yes)
			(effects
				(font
					(size 1 1)
					(thickness 0.15)
				)
			)
		)
		(property "Manufacturer" "Murata"
			(at 438.4 276.85 0)
			(layer "F.Fab")
			(hide yes)
			(effects
				(font
					(size 1 1)
					(thickness 0.15)
				)
			)
		)
		(property "Val" "100n"
			(at 438.4 276.85 0)
			(layer "F.Fab")
			(hide yes)
			(effects
				(font
					(size 1 1)
					(thickness 0.15)
				)
			)
		)
		(property "Voltage" "50V"
			(at 438.4 276.85 0)
			(layer "F.Fab")
			(hide yes)
			(effects
				(font
					(size 1 1)
					(thickness 0.15)
				)
			)
		)
		(sheetname "Clocks")
		(sheetfile "clocks.kicad_sch")
		(attr smd)
		(fp_rect
			(start -0.925 -0.47)
			(end 0.925 0.47)
			(stroke
				(width 0.05)
				(type default)
			)
			(fill no)
			(layer "F.CrtYd")
		)
		(fp_line
			(start 0.504 0.248)
			(end -0.494 0.248)
			(stroke
				(width 0.15)
				(type solid)
			)
			(layer "F.Fab")
		)
		(fp_line
			(start 0.504 -0.25)
			(end 0.504 0.248)
			(stroke
				(width 0.15)
				(type solid)
			)
			(layer "F.Fab")
		)
		(fp_line
			(start -0.494 0.248)
			(end -0.494 -0.25)
			(stroke
				(width 0.15)
				(type solid)
			)
			(layer "F.Fab")
		)
		(fp_line
			(start -0.494 -0.25)
			(end 0.504 -0.25)
			(stroke
				(width 0.15)
				(type solid)
			)
			(layer "F.Fab")
		)
		(pad "1" smd roundrect
			(at -0.48 0 180)
			(size 0.59 0.64)
			(layers "F.Cu" "F.Mask" "F.Paste")
			(roundrect_rratio 0.25)
			(net 24 "+3V3")
			(pintype "passive")
		)
		(pad "2" smd roundrect
			(at 0.48 0 180)
			(size 0.59 0.64)
			(layers "F.Cu" "F.Mask" "F.Paste")
			(roundrect_rratio 0.25)
			(net 1 "GND")
			(pintype "passive")
		)
	)
)
